(kicad_pcb
	(version 20211014)
	(generator pcbnew)
	(general
    (thickness 1.6)
  )
	(paper "A4")
	(title_block
    (title "SA800U (Snapdragon 845) Baseboard")
    (date "2023-10-19")
    (rev "1.0.3")
    (company "Antmicro Ltd.")
    (comment 1 "www.antmicro.com")
		(comment 9 "footprints 472-479 of 589")
	)
	(layers
    (0 "F.Cu" signal)
    (1 "In1.Cu" power)
    (2 "In2.Cu" signal)
    (3 "In3.Cu" signal)
    (4 "In4.Cu" power)
    (31 "B.Cu" signal)
    (32 "B.Adhes" user "B.Adhesive")
    (33 "F.Adhes" user "F.Adhesive")
    (34 "B.Paste" user)
    (35 "F.Paste" user)
    (36 "B.SilkS" user "B.Silkscreen")
    (37 "F.SilkS" user "F.Silkscreen")
    (38 "B.Mask" user)
    (39 "F.Mask" user)
    (40 "Dwgs.User" user "User.Drawings")
    (41 "Cmts.User" user "User.Comments")
    (42 "Eco1.User" user "User.Eco1")
    (43 "Eco2.User" user "User.Eco2")
    (44 "Edge.Cuts" user)
    (45 "Margin" user)
    (46 "B.CrtYd" user "B.Courtyard")
    (47 "F.CrtYd" user "F.Courtyard")
    (48 "B.Fab" user)
    (49 "F.Fab" user)
  )
	(footprint "sa800u-baseboard-hw-footprints:SC70-3" (layer "B.Cu")
    (tedit 615FF353)
    (at 146.8 138.2 -90)
    (property "Author" "Antmicro")
    (property "License" "Apache-2.0")
    (property "MPN" "BSS138PW")
    (property "Manufacturer" "Nexperia")
    (property "Sheetfile" "som.kicad_sch")
    (property "Sheetname" "SoM")
    (attr smd)
    (fp_text reference "Q5" (at 0 1.6 90) (layer "B.SilkS")
      (effects (font (size 0.7 0.7) (thickness 0.15)) (justify left bottom mirror))
    )
    (fp_text value "BSS138PW" (at 0 -2.3 90) (layer "B.Fab")
      (effects (font (size 0.7 0.7) (thickness 0.15)) (justify left bottom mirror))
    )
    (fp_text user "License: Apache-2.0" (at -1.45 -6.782 90) (layer "B.Fab") hide
      (effects (font (size 0.7 0.7) (thickness 0.15)) (justify left bottom mirror))
    )
    (fp_text user "${REFERENCE}" (at -1.45 -4.783 90) (layer "B.Fab") hide
      (effects (font (size 0.7 0.7) (thickness 0.15)) (justify left bottom mirror))
    )
    (fp_text user "Author: Antmicro" (at -1.45 -5.782 90) (layer "B.Fab") hide
      (effects (font (size 0.7 0.7) (thickness 0.15)) (justify left bottom mirror))
    )
    (fp_line (start 0.627 -0.6) (end 0.627 -1.001) (layer "B.SilkS") (width 0.15))
    (fp_line (start 0.627 0.6) (end 0.627 0.999) (layer "B.SilkS") (width 0.15))
    (fp_line (start -0.3 -1) (end 0.627 -1.001) (layer "B.SilkS") (width 0.15))
    (fp_line (start -0.3 1) (end 0.627 0.999) (layer "B.SilkS") (width 0.15))
    (fp_line (start -0.9 -1.3) (end -0.9 -1) (layer "B.CrtYd") (width 0.05))
    (fp_line (start -1.4 -1) (end -1.4 1) (layer "B.CrtYd") (width 0.05))
    (fp_line (start 0.9 1.3) (end 0.9 0.4) (layer "B.CrtYd") (width 0.05))
    (fp_line (start -0.9 -1) (end -1.4 -1) (layer "B.CrtYd") (width 0.05))
    (fp_line (start 1.4 0.4) (end 1.4 -0.4) (layer "B.CrtYd") (width 0.05))
    (fp_line (start 0.9 -1.3) (end -0.9 -1.3) (layer "B.CrtYd") (width 0.05))
    (fp_line (start -0.9 1.3) (end 0.9 1.3) (layer "B.CrtYd") (width 0.05))
    (fp_line (start 0.9 0.4) (end 1.4 0.4) (layer "B.CrtYd") (width 0.05))
    (fp_line (start -0.9 1) (end -1.4 1) (layer "B.CrtYd") (width 0.05))
    (fp_line (start 1.4 -0.4) (end 0.9 -0.4) (layer "B.CrtYd") (width 0.05))
    (fp_line (start 0.9 -0.4) (end 0.9 -1.3) (layer "B.CrtYd") (width 0.05))
    (fp_line (start -0.9 1.3) (end -0.9 1) (layer "B.CrtYd") (width 0.05))
    (fp_rect (start -0.623 0.999) (end 0.627 -1.001) (layer "B.Fab") (width 0.15) (fill none))
    (pad "1" smd rect (at -1.051 0.65 180) (size 0.6 0.6) (layers "B.Cu" "B.Paste" "B.Mask")
      (net 349 "/SoM/BOOT") (pinfunction "G") (pintype "bidirectional"))
    (pad "2" smd rect (at -1.051 -0.65 180) (size 0.6 0.6) (layers "B.Cu" "B.Paste" "B.Mask")
      (net 1 "GND") (pinfunction "S") (pintype "bidirectional"))
    (pad "3" smd rect (at 1.05 0 180) (size 0.6 0.6) (layers "B.Cu" "B.Paste" "B.Mask")
      (net 385 "Net-(Q5-Pad3)") (pinfunction "D") (pintype "bidirectional"))
  )
	(footprint "sa800u-baseboard-hw-footprints:SC70-3" (layer "B.Cu")
    (tedit 615FF353)
    (at 150.35 142.75 90)
    (property "Author" "Antmicro")
    (property "License" "Apache-2.0")
    (property "MPN" "BSS138PW")
    (property "Manufacturer" "Nexperia")
    (property "Sheetfile" "som.kicad_sch")
    (property "Sheetname" "SoM")
    (attr smd)
    (fp_text reference "Q6" (at 0.7 -1.31 270) (layer "B.SilkS")
      (effects (font (size 0.7 0.7) (thickness 0.15)) (justify left bottom mirror))
    )
    (fp_text value "BSS138PW" (at 0 -2.3 270) (layer "B.Fab")
      (effects (font (size 0.7 0.7) (thickness 0.15)) (justify left bottom mirror))
    )
    (fp_text user "Author: Antmicro" (at -1.45 -5.782 270) (layer "B.Fab") hide
      (effects (font (size 0.7 0.7) (thickness 0.15)) (justify left bottom mirror))
    )
    (fp_text user "${REFERENCE}" (at -1.45 -4.783 270) (layer "B.Fab") hide
      (effects (font (size 0.7 0.7) (thickness 0.15)) (justify left bottom mirror))
    )
    (fp_text user "License: Apache-2.0" (at -1.45 -6.782 270) (layer "B.Fab") hide
      (effects (font (size 0.7 0.7) (thickness 0.15)) (justify left bottom mirror))
    )
    (fp_line (start -0.3 -1) (end 0.627 -1.001) (layer "B.SilkS") (width 0.15))
    (fp_line (start 0.627 -0.6) (end 0.627 -1.001) (layer "B.SilkS") (width 0.15))
    (fp_line (start 0.627 0.6) (end 0.627 0.999) (layer "B.SilkS") (width 0.15))
    (fp_line (start -0.3 1) (end 0.627 0.999) (layer "B.SilkS") (width 0.15))
    (fp_line (start -0.9 1) (end -1.4 1) (layer "B.CrtYd") (width 0.05))
    (fp_line (start 0.9 0.4) (end 1.4 0.4) (layer "B.CrtYd") (width 0.05))
    (fp_line (start 0.9 -0.4) (end 0.9 -1.3) (layer "B.CrtYd") (width 0.05))
    (fp_line (start -1.4 -1) (end -1.4 1) (layer "B.CrtYd") (width 0.05))
    (fp_line (start -0.9 1.3) (end 0.9 1.3) (layer "B.CrtYd") (width 0.05))
    (fp_line (start 1.4 0.4) (end 1.4 -0.4) (layer "B.CrtYd") (width 0.05))
    (fp_line (start 0.9 -1.3) (end -0.9 -1.3) (layer "B.CrtYd") (width 0.05))
    (fp_line (start 0.9 1.3) (end 0.9 0.4) (layer "B.CrtYd") (width 0.05))
    (fp_line (start -0.9 -1.3) (end -0.9 -1) (layer "B.CrtYd") (width 0.05))
    (fp_line (start -0.9 1.3) (end -0.9 1) (layer "B.CrtYd") (width 0.05))
    (fp_line (start -0.9 -1) (end -1.4 -1) (layer "B.CrtYd") (width 0.05))
    (fp_line (start 1.4 -0.4) (end 0.9 -0.4) (layer "B.CrtYd") (width 0.05))
    (fp_rect (start -0.623 0.999) (end 0.627 -1.001) (layer "B.Fab") (width 0.15) (fill none))
    (pad "1" smd rect (at -1.051 0.65) (size 0.6 0.6) (layers "B.Cu" "B.Paste" "B.Mask")
      (net 132 "VREG_S4A_1V8") (pinfunction "G") (pintype "bidirectional"))
    (pad "2" smd rect (at -1.051 -0.65) (size 0.6 0.6) (layers "B.Cu" "B.Paste" "B.Mask")
      (net 1 "GND") (pinfunction "S") (pintype "bidirectional"))
    (pad "3" smd rect (at 1.05 0) (size 0.6 0.6) (layers "B.Cu" "B.Paste" "B.Mask")
      (net 386 "Net-(Q6-Pad3)") (pinfunction "D") (pintype "bidirectional"))
  )
	(footprint "sa800u-baseboard-hw-footprints:SC70-3" (layer "B.Cu")
    (tedit 615FF353)
    (at 146.8 135.23 -90)
    (property "Author" "Antmicro")
    (property "License" "Apache-2.0")
    (property "MPN" "BSS138PW")
    (property "Manufacturer" "Nexperia")
    (property "Sheetfile" "som.kicad_sch")
    (property "Sheetname" "SoM")
    (attr smd)
    (fp_text reference "Q7" (at 0 1.6 90) (layer "B.SilkS")
      (effects (font (size 0.7 0.7) (thickness 0.15)) (justify left bottom mirror))
    )
    (fp_text value "BSS138PW" (at 0 -2.3 90) (layer "B.Fab")
      (effects (font (size 0.7 0.7) (thickness 0.15)) (justify left bottom mirror))
    )
    (fp_text user "License: Apache-2.0" (at -1.45 -6.782 90) (layer "B.Fab") hide
      (effects (font (size 0.7 0.7) (thickness 0.15)) (justify left bottom mirror))
    )
    (fp_text user "${REFERENCE}" (at -1.45 -4.783 90) (layer "B.Fab") hide
      (effects (font (size 0.7 0.7) (thickness 0.15)) (justify left bottom mirror))
    )
    (fp_text user "Author: Antmicro" (at -1.45 -5.782 90) (layer "B.Fab") hide
      (effects (font (size 0.7 0.7) (thickness 0.15)) (justify left bottom mirror))
    )
    (fp_line (start -0.3 -1) (end 0.627 -1.001) (layer "B.SilkS") (width 0.15))
    (fp_line (start 0.627 -0.6) (end 0.627 -1.001) (layer "B.SilkS") (width 0.15))
    (fp_line (start -0.3 1) (end 0.627 0.999) (layer "B.SilkS") (width 0.15))
    (fp_line (start 0.627 0.6) (end 0.627 0.999) (layer "B.SilkS") (width 0.15))
    (fp_line (start 0.9 -1.3) (end -0.9 -1.3) (layer "B.CrtYd") (width 0.05))
    (fp_line (start 0.9 1.3) (end 0.9 0.4) (layer "B.CrtYd") (width 0.05))
    (fp_line (start -1.4 -1) (end -1.4 1) (layer "B.CrtYd") (width 0.05))
    (fp_line (start -0.9 -1.3) (end -0.9 -1) (layer "B.CrtYd") (width 0.05))
    (fp_line (start 1.4 -0.4) (end 0.9 -0.4) (layer "B.CrtYd") (width 0.05))
    (fp_line (start 1.4 0.4) (end 1.4 -0.4) (layer "B.CrtYd") (width 0.05))
    (fp_line (start 0.9 -0.4) (end 0.9 -1.3) (layer "B.CrtYd") (width 0.05))
    (fp_line (start 0.9 0.4) (end 1.4 0.4) (layer "B.CrtYd") (width 0.05))
    (fp_line (start -0.9 1.3) (end 0.9 1.3) (layer "B.CrtYd") (width 0.05))
    (fp_line (start -0.9 1.3) (end -0.9 1) (layer "B.CrtYd") (width 0.05))
    (fp_line (start -0.9 -1) (end -1.4 -1) (layer "B.CrtYd") (width 0.05))
    (fp_line (start -0.9 1) (end -1.4 1) (layer "B.CrtYd") (width 0.05))
    (fp_rect (start -0.623 0.999) (end 0.627 -1.001) (layer "B.Fab") (width 0.15) (fill none))
    (pad "1" smd rect (at -1.051 0.65 180) (size 0.6 0.6) (layers "B.Cu" "B.Paste" "B.Mask")
      (net 350 "/SoM/USER_LED") (pinfunction "G") (pintype "bidirectional"))
    (pad "2" smd rect (at -1.051 -0.65 180) (size 0.6 0.6) (layers "B.Cu" "B.Paste" "B.Mask")
      (net 1 "GND") (pinfunction "S") (pintype "bidirectional"))
    (pad "3" smd rect (at 1.05 0 180) (size 0.6 0.6) (layers "B.Cu" "B.Paste" "B.Mask")
      (net 387 "Net-(Q7-Pad3)") (pinfunction "D") (pintype "bidirectional"))
  )
	(footprint "sa800u-baseboard-hw-footprints:C_0402_1005Metric" (layer "B.Cu")
    (tedit 616D63CF)
    (at 144.6 121.4 -90)
    (descr "Capacitor SMD 0402")
    (tags "capacitor SMD 0402")
    (property "Author" "Antmicro")
    (property "DNP" "DNP")
    (property "Dielectric" "")
    (property "License" "Apache-2.0")
    (property "MPN" "CC0402MRX5R5BB106")
    (property "Manufacturer" "Yaego")
    (property "Sheetfile" "hdmi-converter.kicad_sch")
    (property "Sheetname" "HDMI converter")
    (property "Val" "10u")
    (property "Voltage" "")
    (attr exclude_from_pos_files)
    (fp_text reference "C24" (at -3.08 -0.46 90) (layer "B.SilkS")
      (effects (font (size 0.7 0.7) (thickness 0.15)) (justify left bottom mirror))
    )
    (fp_text value "C_10u_0402" (at 0 -1.4 90) (layer "B.Fab")
      (effects (font (size 0.7 0.7) (thickness 0.15)) (justify left bottom mirror))
    )
    (fp_text user "${REFERENCE}" (at -0.932 -3.168 90) (layer "B.Fab") hide
      (effects (font (size 0.7 0.7) (thickness 0.15)) (justify left bottom mirror))
    )
    (fp_text user "Author: Antmicro" (at -0.932 -4.17 90) (layer "B.Fab") hide
      (effects (font (size 0.7 0.7) (thickness 0.15)) (justify left bottom mirror))
    )
    (fp_text user "License: Apache-2.0" (at -0.932 -5.17 90) (layer "B.Fab") hide
      (effects (font (size 0.7 0.7) (thickness 0.15)) (justify left bottom mirror))
    )
    (fp_rect (start -0.94 0.47) (end 0.94 -0.47) (layer "B.CrtYd") (width 0.05) (fill none))
    (fp_rect (start -0.499 0.249) (end 0.499 -0.249) (layer "B.Fab") (width 0.15) (fill none))
    (pad "1" smd roundrect (at -0.484 0 270) (size 0.59 0.64) (layers "B.Cu" "B.Paste" "B.Mask") (roundrect_rratio 0.25)
      (net 189 "/HDMI converter/LT9611_VCC12_RX") (pintype "passive"))
    (pad "2" smd roundrect (at 0.484 0 270) (size 0.59 0.64) (layers "B.Cu" "B.Paste" "B.Mask") (roundrect_rratio 0.25)
      (net 1 "GND") (pintype "passive"))
  )
	(footprint "sa800u-baseboard-hw-footprints:R_0402_1005Metric" (layer "B.Cu")
    (tedit 5FD9C158)
    (at 133.485 133.5)
    (descr "Resistor SMD 0402")
    (tags "resistor SMD 0402")
    (property "Author" "Antmicro")
    (property "License" "Apache-2.0")
    (property "MPN" "CR0402-FX-1002GLF")
    (property "Manufacturer" "Bourns")
    (property "Sheetfile" "hdmi-converter.kicad_sch")
    (property "Sheetname" "HDMI converter")
    (property "Tolerance" "1%")
    (property "Val" "10k")
    (attr smd)
    (fp_text reference "R50" (at 0.955 -0.59 180) (layer "B.SilkS")
      (effects (font (size 0.7 0.7) (thickness 0.15)) (justify left bottom mirror))
    )
    (fp_text value "R_10k_0402" (at 0 -1.4 180) (layer "B.Fab")
      (effects (font (size 0.7 0.7) (thickness 0.15)) (justify left bottom mirror))
    )
    (fp_text user "Author: Antmicro" (at -0.95 -4.169 180) (layer "B.Fab") hide
      (effects (font (size 0.7 0.7) (thickness 0.15)) (justify left bottom mirror))
    )
    (fp_text user "${REFERENCE}" (at -0.95 -3.168 180) (layer "B.Fab") hide
      (effects (font (size 0.7 0.7) (thickness 0.15)) (justify left bottom mirror))
    )
    (fp_text user "License: Apache-2.0" (at -0.95 -5.169 180) (layer "B.Fab") hide
      (effects (font (size 0.7 0.7) (thickness 0.15)) (justify left bottom mirror))
    )
    (fp_rect (start -0.93 0.47) (end 0.93 -0.47) (layer "B.CrtYd") (width 0.05) (fill none))
    (fp_rect (start -0.5 0.25) (end 0.5 -0.25) (layer "B.Fab") (width 0.15) (fill none))
    (pad "1" smd roundrect (at -0.485 0) (size 0.59 0.64) (layers "B.Cu" "B.Paste" "B.Mask") (roundrect_rratio 0.25)
      (net 131 "3V3_SYS") (pintype "passive"))
    (pad "2" smd roundrect (at 0.485 0) (size 0.59 0.64) (layers "B.Cu" "B.Paste" "B.Mask") (roundrect_rratio 0.25)
      (net 155 "Net-(Q4-Pad1)") (pintype "passive"))
  )
	(footprint "sa800u-baseboard-hw-footprints:C_0402_1005Metric" (layer "B.Cu")
    (tedit 616D63CF)
    (at 142.55 121.4 -90)
    (descr "Capacitor SMD 0402")
    (tags "capacitor SMD 0402")
    (property "Author" "Antmicro")
    (property "Dielectric" "X5R")
    (property "License" "Apache-2.0")
    (property "MPN" "GRM155R61H104KE14D")
    (property "Manufacturer" "Murata")
    (property "Sheetfile" "hdmi-converter.kicad_sch")
    (property "Sheetname" "HDMI converter")
    (property "Val" "100n")
    (property "Voltage" "50V")
    (attr smd)
    (fp_text reference "C27" (at -3.08 -0.46 90) (layer "B.SilkS")
      (effects (font (size 0.7 0.7) (thickness 0.15)) (justify left bottom mirror))
    )
    (fp_text value "C_100n_0402" (at 0 -1.4 90) (layer "B.Fab")
      (effects (font (size 0.7 0.7) (thickness 0.15)) (justify left bottom mirror))
    )
    (fp_text user "Author: Antmicro" (at -0.932 -4.17 90) (layer "B.Fab") hide
      (effects (font (size 0.7 0.7) (thickness 0.15)) (justify left bottom mirror))
    )
    (fp_text user "License: Apache-2.0" (at -0.932 -5.17 90) (layer "B.Fab") hide
      (effects (font (size 0.7 0.7) (thickness 0.15)) (justify left bottom mirror))
    )
    (fp_text user "${REFERENCE}" (at -0.932 -3.168 90) (layer "B.Fab") hide
      (effects (font (size 0.7 0.7) (thickness 0.15)) (justify left bottom mirror))
    )
    (fp_rect (start -0.94 0.47) (end 0.94 -0.47) (layer "B.CrtYd") (width 0.05) (fill none))
    (fp_rect (start -0.499 0.249) (end 0.499 -0.249) (layer "B.Fab") (width 0.15) (fill none))
    (pad "1" smd roundrect (at -0.484 0 270) (size 0.59 0.64) (layers "B.Cu" "B.Paste" "B.Mask") (roundrect_rratio 0.25)
      (net 189 "/HDMI converter/LT9611_VCC12_RX") (pintype "passive"))
    (pad "2" smd roundrect (at 0.484 0 270) (size 0.59 0.64) (layers "B.Cu" "B.Paste" "B.Mask") (roundrect_rratio 0.25)
      (net 1 "GND") (pintype "passive"))
  )
	(footprint "sa800u-baseboard-hw-footprints:SC70-3" (layer "B.Cu")
    (tedit 615FF353)
    (at 134.6 135.4 -90)
    (property "Author" "Antmicro")
    (property "License" "Apache-2.0")
    (property "MPN" "BSS138PW")
    (property "Manufacturer" "Nexperia")
    (property "Sheetfile" "hdmi-converter.kicad_sch")
    (property "Sheetname" "HDMI converter")
    (attr smd)
    (fp_text reference "Q4" (at 0.71 0.59 90) (layer "B.SilkS")
      (effects (font (size 0.7 0.7) (thickness 0.15)) (justify left bottom mirror))
    )
    (fp_text value "BSS138PW" (at 0 -2.3 90) (layer "B.Fab")
      (effects (font (size 0.7 0.7) (thickness 0.15)) (justify left bottom mirror))
    )
    (fp_text user "${REFERENCE}" (at -1.45 -4.783 90) (layer "B.Fab") hide
      (effects (font (size 0.7 0.7) (thickness 0.15)) (justify left bottom mirror))
    )
    (fp_text user "Author: Antmicro" (at -1.45 -5.782 90) (layer "B.Fab") hide
      (effects (font (size 0.7 0.7) (thickness 0.15)) (justify left bottom mirror))
    )
    (fp_text user "License: Apache-2.0" (at -1.45 -6.782 90) (layer "B.Fab") hide
      (effects (font (size 0.7 0.7) (thickness 0.15)) (justify left bottom mirror))
    )
    (fp_line (start -0.3 1) (end 0.627 0.999) (layer "B.SilkS") (width 0.15))
    (fp_line (start -0.3 -1) (end 0.627 -1.001) (layer "B.SilkS") (width 0.15))
    (fp_line (start 0.627 -0.6) (end 0.627 -1.001) (layer "B.SilkS") (width 0.15))
    (fp_line (start 0.627 0.6) (end 0.627 0.999) (layer "B.SilkS") (width 0.15))
    (fp_line (start 0.9 0.4) (end 1.4 0.4) (layer "B.CrtYd") (width 0.05))
    (fp_line (start 1.4 0.4) (end 1.4 -0.4) (layer "B.CrtYd") (width 0.05))
    (fp_line (start -0.9 1.3) (end -0.9 1) (layer "B.CrtYd") (width 0.05))
    (fp_line (start -0.9 -1) (end -1.4 -1) (layer "B.CrtYd") (width 0.05))
    (fp_line (start 0.9 -1.3) (end -0.9 -1.3) (layer "B.CrtYd") (width 0.05))
    (fp_line (start -0.9 1) (end -1.4 1) (layer "B.CrtYd") (width 0.05))
    (fp_line (start 1.4 -0.4) (end 0.9 -0.4) (layer "B.CrtYd") (width 0.05))
    (fp_line (start -1.4 -1) (end -1.4 1) (layer "B.CrtYd") (width 0.05))
    (fp_line (start -0.9 -1.3) (end -0.9 -1) (layer "B.CrtYd") (width 0.05))
    (fp_line (start -0.9 1.3) (end 0.9 1.3) (layer "B.CrtYd") (width 0.05))
    (fp_line (start 0.9 -0.4) (end 0.9 -1.3) (layer "B.CrtYd") (width 0.05))
    (fp_line (start 0.9 1.3) (end 0.9 0.4) (layer "B.CrtYd") (width 0.05))
    (fp_rect (start -0.623 0.999) (end 0.627 -1.001) (layer "B.Fab") (width 0.15) (fill none))
    (pad "1" smd rect (at -1.051 0.65 180) (size 0.6 0.6) (layers "B.Cu" "B.Paste" "B.Mask")
      (net 155 "Net-(Q4-Pad1)") (pinfunction "G") (pintype "bidirectional"))
    (pad "2" smd rect (at -1.051 -0.65 180) (size 0.6 0.6) (layers "B.Cu" "B.Paste" "B.Mask")
      (net 1 "GND") (pinfunction "S") (pintype "bidirectional"))
    (pad "3" smd rect (at 1.05 0 180) (size 0.6 0.6) (layers "B.Cu" "B.Paste" "B.Mask")
      (net 209 "/HDMI converter/VCOM") (pinfunction "D") (pintype "bidirectional"))
  )
	(footprint "sa800u-baseboard-hw-footprints:C_0402_1005Metric" (layer "B.Cu")
    (tedit 616D63CF)
    (at 134.600003 123.066848 180)
    (descr "Capacitor SMD 0402")
    (tags "capacitor SMD 0402")
    (property "Author" "Antmicro")
    (property "Dielectric" "")
    (property "License" "Apache-2.0")
    (property "MPN" "C1005X6S1A105K050BC")
    (property "Manufacturer" "TDK")
    (property "Sheetfile" "hdmi-converter.kicad_sch")
    (property "Sheetname" "HDMI converter")
    (property "Val" "1u")
    (property "Voltage" "")
    (attr smd)
    (fp_text reference "C25" (at 0.820003 -0.453151) (layer "B.SilkS")
      (effects (font (size 0.7 0.7) (thickness 0.15)) (justify left bottom mirror))
    )
    (fp_text value "C_1u_0402" (at 0 -1.4) (layer "B.Fab")
      (effects (font (size 0.7 0.7) (thickness 0.15)) (justify left bottom mirror))
    )
    (fp_text user "Author: Antmicro" (at -0.932 -4.17) (layer "B.Fab") hide
      (effects (font (size 0.7 0.7) (thickness 0.15)) (justify left bottom mirror))
    )
    (fp_text user "${REFERENCE}" (at -0.932 -3.168) (layer "B.Fab") hide
      (effects (font (size 0.7 0.7) (thickness 0.15)) (justify left bottom mirror))
    )
    (fp_text user "License: Apache-2.0" (at -0.932 -5.17) (layer "B.Fab") hide
      (effects (font (size 0.7 0.7) (thickness 0.15)) (justify left bottom mirror))
    )
    (fp_rect (start -0.94 0.47) (end 0.94 -0.47) (layer "B.CrtYd") (width 0.05) (fill none))
    (fp_rect (start -0.499 0.249) (end 0.499 -0.249) (layer "B.Fab") (width 0.15) (fill none))
    (pad "1" smd roundrect (at -0.484 0 180) (size 0.59 0.64) (layers "B.Cu" "B.Paste" "B.Mask") (roundrect_rratio 0.25)
      (net 188 "/HDMI converter/LT9611_VDD12") (pintype "passive"))
    (pad "2" smd roundrect (at 0.484 0 180) (size 0.59 0.64) (layers "B.Cu" "B.Paste" "B.Mask") (roundrect_rratio 0.25)
      (net 1 "GND") (pintype "passive"))
  )
)
